# T6G (Grand Teton) — schematic netlist excerpt (pin names and nets, part order shuffled) for the footprints in the layout excerpt that follows; sources: Cadence DE-HDL packaged netlist, KiCad conversion of 04192023_DAF0TMB3IC0_F0TG_MB_C_brd_V02_OCP.brd

R1579  Q_RES  49.9 1% CHIP  pkg 0402LF  page 97 : A = I3C_SPD_DDRGL_CPU0_SCL ; B = I3C_SPD_DDRL_CPU0_SCL
C3  Q_CAP  0.1UF 25V 10% X7R  pkg 0402  page 160 : A = PVDD11_S3_P0 ; B = GND

(kicad_pcb
	(version 20260206)
	(generator "pcbnew")
	(generator_version "10.0")
	(general
		(thickness 1.6)
		(legacy_teardrops no)
	)
	(paper "A4")
	(title_block
		(title "04192023_DAF0TMB3IC0_F0TG_MB_C_brd_V02_OCP.brd")
		(comment 1 "Grand Teton / footprints 6240-6241 of 8354")
	)
	(layers
		(0 "F.Cu" signal "TOP")
		(4 "In1.Cu" signal "GND")
		(6 "In2.Cu" signal "IN1")
		(8 "In3.Cu" signal "GND1")
		(10 "In4.Cu" signal "IN2")
		(12 "In5.Cu" signal "GND2")
		(14 "In6.Cu" signal "IN3")
		(16 "In7.Cu" signal "GND3")
		(18 "In8.Cu" signal "VCC")
		(20 "In9.Cu" signal "VCC1")
		(22 "In10.Cu" signal "GND4")
		(24 "In11.Cu" signal "IN4")
		(26 "In12.Cu" signal "GND5")
		(28 "In13.Cu" signal "IN5")
		(30 "In14.Cu" signal "GND6")
		(32 "In15.Cu" signal "IN6")
		(34 "In16.Cu" signal "GND7")
		(2 "B.Cu" signal "BOTTOM")
		(9 "F.Adhes" user "F.Adhesive")
		(11 "B.Adhes" user "B.Adhesive")
		(13 "F.Paste" user "Package Geometry/Pastemask Top")
		(15 "B.Paste" user "Package Geometry/Pastemask Bottom")
		(5 "F.SilkS" user "Ref Des/Silkscreen Top")
		(7 "B.SilkS" user "Ref Des/Silkscreen Bottom")
		(1 "F.Mask" user "Board Geometry/Soldermask Top")
		(3 "B.Mask" user "Board Geometry/Soldermask Bottom")
		(17 "Dwgs.User" user "User.Drawings")
		(19 "Cmts.User" user "User.Comments")
		(21 "Eco1.User" user "User.Eco1")
		(23 "Eco2.User" user "User.Eco2")
		(25 "Edge.Cuts" user "Board Geometry/Outline")
		(27 "Margin" user)
		(31 "F.CrtYd" user "Package Geometry/Place Bound Top")
		(29 "B.CrtYd" user "Package Geometry/Place Bound Bottom")
		(35 "F.Fab" user "Ref Des/Assembly Top")
		(33 "B.Fab" user "Ref Des/Assembly Bottom")
	)
	(footprint ""
		(layer "B.Cu")
		(at 232.537 -218.059 90)
		(property "Reference" "C3"
			(at 0 0 90)
			(layer "B.SilkS")
			(hide yes)
			(effects
				(font
					(size 1.27 1.27)
				)
				(justify mirror)
			)
		)
		(property "Value" ""
			(at 0 0 90)
			(layer "B.Fab")
			(effects
				(font
					(size 1.27 1.27)
				)
				(justify mirror)
			)
		)
		(duplicate_pad_numbers_are_jumpers no)
		(fp_line
			(start 0.7874 -0.4064)
			(end -0.7874 -0.4064)
			(stroke
				(width 0.1524)
				(type default)
			)
			(layer "B.SilkS")
		)
		(fp_line
			(start -0.7874 -0.4064)
			(end -0.7874 0.4064)
			(stroke
				(width 0.1524)
				(type default)
			)
			(layer "B.SilkS")
		)
		(fp_line
			(start 0.7874 0.4064)
			(end 0.7874 -0.4064)
			(stroke
				(width 0.1524)
				(type default)
			)
			(layer "B.SilkS")
		)
		(fp_line
			(start -0.7874 0.4064)
			(end 0.7874 0.4064)
			(stroke
				(width 0.1524)
				(type default)
			)
			(layer "B.SilkS")
		)
		(fp_line
			(start 0.67945 -0.305054)
			(end 0.12065 -0.305054)
			(stroke
				(width 0.1)
				(type default)
			)
			(layer "B.Fab")
		)
		(fp_line
			(start 0.12065 -0.305054)
			(end 0.12065 -0.2794)
			(stroke
				(width 0.1)
				(type default)
			)
			(layer "B.Fab")
		)
		(fp_line
			(start -0.12065 -0.3048)
			(end -0.67945 -0.3048)
			(stroke
				(width 0.1)
				(type default)
			)
			(layer "B.Fab")
		)
		(fp_line
			(start -0.67945 -0.3048)
			(end -0.67945 0.3048)
			(stroke
				(width 0.1)
				(type default)
			)
			(layer "B.Fab")
		)
		(fp_line
			(start 0.12065 -0.2794)
			(end -0.12065 -0.2794)
			(stroke
				(width 0.1)
				(type default)
			)
			(layer "B.Fab")
		)
		(fp_line
			(start -0.12065 -0.2794)
			(end -0.12065 -0.3048)
			(stroke
				(width 0.1)
				(type default)
			)
			(layer "B.Fab")
		)
		(fp_line
			(start 0.12065 0.2794)
			(end 0.12065 0.3048)
			(stroke
				(width 0.1)
				(type default)
			)
			(layer "B.Fab")
		)
		(fp_line
			(start -0.120396 0.2794)
			(end 0.12065 0.2794)
			(stroke
				(width 0.1)
				(type default)
			)
			(layer "B.Fab")
		)
		(fp_line
			(start 0.67945 0.3048)
			(end 0.67945 -0.305054)
			(stroke
				(width 0.1)
				(type default)
			)
			(layer "B.Fab")
		)
		(fp_line
			(start 0.12065 0.3048)
			(end 0.67945 0.3048)
			(stroke
				(width 0.1)
				(type default)
			)
			(layer "B.Fab")
		)
		(fp_line
			(start -0.120396 0.3048)
			(end -0.120396 0.2794)
			(stroke
				(width 0.1)
				(type default)
			)
			(layer "B.Fab")
		)
		(fp_line
			(start -0.67945 0.3048)
			(end -0.120396 0.3048)
			(stroke
				(width 0.1)
				(type default)
			)
			(layer "B.Fab")
		)
		(pad "1" smd circle
			(at 0.40005 0 270)
			(size 0 0)
			(layers "B.Cu" "B.Mask" "B.Paste")
			(net "PVDD11_S3_P0")
		)
		(pad "2" smd circle
			(at -0.40005 0 270)
			(size 0 0)
			(layers "B.Cu" "B.Mask" "B.Paste")
			(net "GND")
		)
	)
	(footprint ""
		(layer "B.Cu")
		(at 453.432418 -194.96151 180)
		(property "Reference" "R1579"
			(at 0 0 0)
			(layer "B.SilkS")
			(hide yes)
			(effects
				(font
					(size 1.27 1.27)
				)
				(justify mirror)
			)
		)
		(property "Value" ""
			(at 0 0 0)
			(layer "B.Fab")
			(effects
				(font
					(size 1.27 1.27)
				)
				(justify mirror)
			)
		)
		(duplicate_pad_numbers_are_jumpers no)
		(fp_line
			(start 0.7874 0.4064)
			(end 0.7874 -0.4064)
			(stroke
				(width 0.1524)
				(type default)
			)
			(layer "B.SilkS")
		)
		(fp_line
			(start 0.7874 -0.4064)
			(end -0.7874 -0.4064)
			(stroke
				(width 0.1524)
				(type default)
			)
			(layer "B.SilkS")
		)
		(fp_line
			(start -0.7874 0.4064)
			(end 0.7874 0.4064)
			(stroke
				(width 0.1524)
				(type default)
			)
			(layer "B.SilkS")
		)
		(fp_line
			(start -0.7874 -0.4064)
			(end -0.7874 0.4064)
			(stroke
				(width 0.1524)
				(type default)
			)
			(layer "B.SilkS")
		)
		(fp_line
			(start 0.67945 0.3048)
			(end 0.67945 -0.305054)
			(stroke
				(width 0.1)
				(type default)
			)
			(layer "B.Fab")
		)
		(fp_line
			(start 0.67945 -0.305054)
			(end 0.12065 -0.305054)
			(stroke
				(width 0.1)
				(type default)
			)
			(layer "B.Fab")
		)
		(fp_line
			(start 0.12065 0.3048)
			(end 0.67945 0.3048)
			(stroke
				(width 0.1)
				(type default)
			)
			(layer "B.Fab")
		)
		(fp_line
			(start 0.12065 0.2794)
			(end 0.12065 0.3048)
			(stroke
				(width 0.1)
				(type default)
			)
			(layer "B.Fab")
		)
		(fp_line
			(start 0.12065 -0.2794)
			(end -0.12065 -0.2794)
			(stroke
				(width 0.1)
				(type default)
			)
			(layer "B.Fab")
		)
		(fp_line
			(start 0.12065 -0.305054)
			(end 0.12065 -0.2794)
			(stroke
				(width 0.1)
				(type default)
			)
			(layer "B.Fab")
		)
		(fp_line
			(start -0.120396 0.3048)
			(end -0.120396 0.2794)
			(stroke
				(width 0.1)
				(type default)
			)
			(layer "B.Fab")
		)
		(fp_line
			(start -0.120396 0.2794)
			(end 0.12065 0.2794)
			(stroke
				(width 0.1)
				(type default)
			)
			(layer "B.Fab")
		)
		(fp_line
			(start -0.12065 -0.2794)
			(end -0.12065 -0.3048)
			(stroke
				(width 0.1)
				(type default)
			)
			(layer "B.Fab")
		)
		(fp_line
			(start -0.12065 -0.3048)
			(end -0.67945 -0.3048)
			(stroke
				(width 0.1)
				(type default)
			)
			(layer "B.Fab")
		)
		(fp_line
			(start -0.67945 0.3048)
			(end -0.120396 0.3048)
			(stroke
				(width 0.1)
				(type default)
			)
			(layer "B.Fab")
		)
		(fp_line
			(start -0.67945 -0.3048)
			(end -0.67945 0.3048)
			(stroke
				(width 0.1)
				(type default)
			)
			(layer "B.Fab")
		)
		(pad "1" smd circle
			(at 0.40005 0)
			(size 0 0)
			(layers "B.Cu" "B.Mask" "B.Paste")
			(net "I3C_SPD_DDRGL_CPU0_SCL")
		)
		(pad "2" smd circle
			(at -0.40005 0)
			(size 0 0)
			(layers "B.Cu" "B.Mask" "B.Paste")
			(net "I3C_SPD_DDRL_CPU0_SCL")
		)
	)
)
